(kicad_pcb
	(version 20260206)
	(generator "pcbnew")
	(generator_version "10.0")
	(general
		(thickness 1.6)
		(legacy_teardrops no)
	)
	(paper "A4")
	(title_block
		(title "04192023_DAF0TMB3IC0_F0TG_MB_C_brd_V02_OCP.brd")
		(comment 1 "Grand Teton / footprints 2408-2415 of 8354")
	)
	(layers
		(0 "F.Cu" signal "TOP")
		(4 "In1.Cu" signal "GND")
		(6 "In2.Cu" signal "IN1")
		(8 "In3.Cu" signal "GND1")
		(10 "In4.Cu" signal "IN2")
		(12 "In5.Cu" signal "GND2")
		(14 "In6.Cu" signal "IN3")
		(16 "In7.Cu" signal "GND3")
		(18 "In8.Cu" signal "VCC")
		(20 "In9.Cu" signal "VCC1")
		(22 "In10.Cu" signal "GND4")
		(24 "In11.Cu" signal "IN4")
		(26 "In12.Cu" signal "GND5")
		(28 "In13.Cu" signal "IN5")
		(30 "In14.Cu" signal "GND6")
		(32 "In15.Cu" signal "IN6")
		(34 "In16.Cu" signal "GND7")
		(2 "B.Cu" signal "BOTTOM")
		(9 "F.Adhes" user "F.Adhesive")
		(11 "B.Adhes" user "B.Adhesive")
		(13 "F.Paste" user "Package Geometry/Pastemask Top")
		(15 "B.Paste" user "Package Geometry/Pastemask Bottom")
		(5 "F.SilkS" user "Ref Des/Silkscreen Top")
		(7 "B.SilkS" user "Ref Des/Silkscreen Bottom")
		(1 "F.Mask" user "Board Geometry/Soldermask Top")
		(3 "B.Mask" user "Board Geometry/Soldermask Bottom")
		(17 "Dwgs.User" user "User.Drawings")
		(19 "Cmts.User" user "User.Comments")
		(21 "Eco1.User" user "User.Eco1")
		(23 "Eco2.User" user "User.Eco2")
		(25 "Edge.Cuts" user "Board Geometry/Outline")
		(27 "Margin" user)
		(31 "F.CrtYd" user "Package Geometry/Place Bound Top")
		(29 "B.CrtYd" user "Package Geometry/Place Bound Bottom")
		(35 "F.Fab" user "Ref Des/Assembly Top")
		(33 "B.Fab" user "Ref Des/Assembly Bottom")
	)
	(footprint ""
		(layer "F.Cu")
		(at 418.212778 -161.102548 -90)
		(property "Reference" "PC606"
			(at 0 0 270)
			(layer "F.SilkS")
			(hide yes)
			(effects
				(font
					(size 1.27 1.27)
				)
			)
		)
		(property "Value" ""
			(at 0 0 270)
			(layer "F.Fab")
			(effects
				(font
					(size 1.27 1.27)
				)
			)
		)
		(duplicate_pad_numbers_are_jumpers no)
		(fp_line
			(start -0.7874 0.4064)
			(end -0.7874 -0.4064)
			(stroke
				(width 0.1524)
				(type default)
			)
			(layer "F.SilkS")
		)
		(fp_line
			(start -0.085852 0.4064)
			(end -0.7874 0.4064)
			(stroke
				(width 0.1524)
				(type default)
			)
			(layer "F.SilkS")
		)
		(fp_line
			(start 0.7874 0.4064)
			(end 0.396748 0.4064)
			(stroke
				(width 0.1524)
				(type default)
			)
			(layer "F.SilkS")
		)
		(fp_line
			(start -0.7874 -0.4064)
			(end 0.7874 -0.4064)
			(stroke
				(width 0.1524)
				(type default)
			)
			(layer "F.SilkS")
		)
		(fp_line
			(start 0.7874 -0.4064)
			(end 0.7874 0.4064)
			(stroke
				(width 0.1524)
				(type default)
			)
			(layer "F.SilkS")
		)
		(fp_line
			(start -0.67945 0.3048)
			(end -0.67945 -0.305054)
			(stroke
				(width 0.1)
				(type default)
			)
			(layer "F.Fab")
		)
		(fp_line
			(start -0.12065 0.3048)
			(end -0.67945 0.3048)
			(stroke
				(width 0.1)
				(type default)
			)
			(layer "F.Fab")
		)
		(fp_line
			(start 0.120396 0.3048)
			(end 0.120396 0.2794)
			(stroke
				(width 0.1)
				(type default)
			)
			(layer "F.Fab")
		)
		(fp_line
			(start 0.67945 0.3048)
			(end 0.120396 0.3048)
			(stroke
				(width 0.1)
				(type default)
			)
			(layer "F.Fab")
		)
		(fp_line
			(start -0.12065 0.2794)
			(end -0.12065 0.3048)
			(stroke
				(width 0.1)
				(type default)
			)
			(layer "F.Fab")
		)
		(fp_line
			(start 0.120396 0.2794)
			(end -0.12065 0.2794)
			(stroke
				(width 0.1)
				(type default)
			)
			(layer "F.Fab")
		)
		(fp_line
			(start -0.12065 -0.2794)
			(end 0.12065 -0.2794)
			(stroke
				(width 0.1)
				(type default)
			)
			(layer "F.Fab")
		)
		(fp_line
			(start 0.12065 -0.2794)
			(end 0.12065 -0.3048)
			(stroke
				(width 0.1)
				(type default)
			)
			(layer "F.Fab")
		)
		(fp_line
			(start 0.12065 -0.3048)
			(end 0.67945 -0.3048)
			(stroke
				(width 0.1)
				(type default)
			)
			(layer "F.Fab")
		)
		(fp_line
			(start 0.67945 -0.3048)
			(end 0.67945 0.3048)
			(stroke
				(width 0.1)
				(type default)
			)
			(layer "F.Fab")
		)
		(fp_line
			(start -0.67945 -0.305054)
			(end -0.12065 -0.305054)
			(stroke
				(width 0.1)
				(type default)
			)
			(layer "F.Fab")
		)
		(fp_line
			(start -0.12065 -0.305054)
			(end -0.12065 -0.2794)
			(stroke
				(width 0.1)
				(type default)
			)
			(layer "F.Fab")
		)
		(pad "1" smd circle
			(at -0.40005 0 270)
			(size 0 0)
			(layers "F.Cu" "F.Mask" "F.Paste")
			(net "PVDDCR_SOC_P0_VCC3")
		)
		(pad "2" smd circle
			(at 0.40005 0 270)
			(size 0 0)
			(layers "F.Cu" "F.Mask" "F.Paste")
			(net "GND")
		)
	)
	(footprint ""
		(layer "F.Cu")
		(at 162.218116 -33.723834 90)
		(property "Reference" "U157"
			(at -0.75946 -2.367788 90)
			(unlocked yes)
			(layer "F.SilkS")
			(effects
				(font
					(size 0.7874 0.5842)
					(thickness 0.1524)
				)
				(justify left)
			)
		)
		(property "Value" ""
			(at 0 0 90)
			(layer "F.Fab")
			(effects
				(font
					(size 1.27 1.27)
				)
			)
		)
		(duplicate_pad_numbers_are_jumpers no)
		(fp_line
			(start 1.733296 -1.549908)
			(end 0.660908 -1.549908)
			(stroke
				(width 0.1524)
				(type default)
			)
			(layer "F.SilkS")
		)
		(fp_line
			(start 0.660908 -1.549908)
			(end 0 -0.889)
			(stroke
				(width 0.1524)
				(type default)
			)
			(layer "F.SilkS")
		)
		(fp_line
			(start -0.660908 -1.549908)
			(end -1.733296 -1.549908)
			(stroke
				(width 0.1524)
				(type default)
			)
			(layer "F.SilkS")
		)
		(fp_line
			(start -1.733296 -1.549908)
			(end -1.733296 1.549908)
			(stroke
				(width 0.1524)
				(type default)
			)
			(layer "F.SilkS")
		)
		(fp_line
			(start 0 -0.889)
			(end -0.660908 -1.549908)
			(stroke
				(width 0.1524)
				(type default)
			)
			(layer "F.SilkS")
		)
		(fp_line
			(start 1.733296 1.549908)
			(end 1.733296 -1.549908)
			(stroke
				(width 0.1524)
				(type default)
			)
			(layer "F.SilkS")
		)
		(fp_line
			(start -1.733296 1.549908)
			(end 1.733296 1.549908)
			(stroke
				(width 0.1524)
				(type default)
			)
			(layer "F.SilkS")
		)
		(fp_poly
			(pts
				(xy -1.9304 -0.94996) (xy -2.4384 -0.69596) (xy -2.4384 -1.20396)
			)
			(stroke
				(width 0)
				(type default)
			)
			(fill yes)
			(layer "F.SilkS")
		)
		(fp_line
			(start 0.849884 -1.549908)
			(end -0.849884 -1.549908)
			(stroke
				(width 0.1)
				(type default)
			)
			(layer "F.Fab")
		)
		(fp_line
			(start -0.849884 -1.549908)
			(end -0.849884 1.549908)
			(stroke
				(width 0.1)
				(type default)
			)
			(layer "F.Fab")
		)
		(fp_line
			(start 0.849884 1.549908)
			(end 0.849884 -1.549908)
			(stroke
				(width 0.1)
				(type default)
			)
			(layer "F.Fab")
		)
		(fp_line
			(start -0.849884 1.549908)
			(end 0.849884 1.549908)
			(stroke
				(width 0.1)
				(type default)
			)
			(layer "F.Fab")
		)
		(fp_poly
			(pts
				(xy -2.4384 -1.20396) (xy -2.4384 -0.69596) (xy -1.9304 -0.94996)
			)
			(stroke
				(width 0)
				(type default)
			)
			(fill yes)
			(layer "F.Fab")
		)
		(pad "1" smd rect
			(at -1.199896 -0.94996)
			(size 0.5588 0.8128)
			(layers "F.Cu" "F.Mask" "F.Paste")
			(net "NC_U157_NC1")
		)
		(pad "2" smd rect
			(at -1.199896 0)
			(size 0.5588 0.8128)
			(layers "F.Cu" "F.Mask" "F.Paste")
			(net "OCP_SFF_WAKE_BUFF_R_N")
		)
		(pad "3" smd rect
			(at -1.199896 0.94996)
			(size 0.5588 0.8128)
			(layers "F.Cu" "F.Mask" "F.Paste")
			(net "GND")
		)
		(pad "4" smd rect
			(at 1.199896 0.94996)
			(size 0.5588 0.8128)
			(layers "F.Cu" "F.Mask" "F.Paste")
			(net "IRQ_LVC3_WAKE_BUF_N")
		)
		(pad "5" smd rect
			(at 1.199896 -0.94996)
			(size 0.5588 0.8128)
			(layers "F.Cu" "F.Mask" "F.Paste")
			(net "P3V3_AUX")
		)
	)
	(footprint ""
		(layer "F.Cu")
		(at 184.605422 -133.565646 -90)
		(property "Reference" "R6806"
			(at 0 0 270)
			(layer "F.SilkS")
			(hide yes)
			(effects
				(font
					(size 1.27 1.27)
				)
			)
		)
		(property "Value" ""
			(at 0 0 270)
			(layer "F.Fab")
			(effects
				(font
					(size 1.27 1.27)
				)
			)
		)
		(duplicate_pad_numbers_are_jumpers no)
		(fp_line
			(start -0.7874 0.4064)
			(end -0.7874 -0.4064)
			(stroke
				(width 0.1524)
				(type default)
			)
			(layer "F.SilkS")
		)
		(fp_line
			(start 0.7874 0.4064)
			(end -0.7874 0.4064)
			(stroke
				(width 0.1524)
				(type default)
			)
			(layer "F.SilkS")
		)
		(fp_line
			(start -0.7874 -0.4064)
			(end 0.7874 -0.4064)
			(stroke
				(width 0.1524)
				(type default)
			)
			(layer "F.SilkS")
		)
		(fp_line
			(start 0.7874 -0.4064)
			(end 0.7874 0.4064)
			(stroke
				(width 0.1524)
				(type default)
			)
			(layer "F.SilkS")
		)
		(fp_line
			(start -0.67945 0.3048)
			(end -0.67945 -0.305054)
			(stroke
				(width 0.1)
				(type default)
			)
			(layer "F.Fab")
		)
		(fp_line
			(start -0.12065 0.3048)
			(end -0.67945 0.3048)
			(stroke
				(width 0.1)
				(type default)
			)
			(layer "F.Fab")
		)
		(fp_line
			(start 0.120396 0.3048)
			(end 0.120396 0.2794)
			(stroke
				(width 0.1)
				(type default)
			)
			(layer "F.Fab")
		)
		(fp_line
			(start 0.67945 0.3048)
			(end 0.120396 0.3048)
			(stroke
				(width 0.1)
				(type default)
			)
			(layer "F.Fab")
		)
		(fp_line
			(start -0.12065 0.2794)
			(end -0.12065 0.3048)
			(stroke
				(width 0.1)
				(type default)
			)
			(layer "F.Fab")
		)
		(fp_line
			(start 0.120396 0.2794)
			(end -0.12065 0.2794)
			(stroke
				(width 0.1)
				(type default)
			)
			(layer "F.Fab")
		)
		(fp_line
			(start -0.12065 -0.2794)
			(end 0.12065 -0.2794)
			(stroke
				(width 0.1)
				(type default)
			)
			(layer "F.Fab")
		)
		(fp_line
			(start 0.12065 -0.2794)
			(end 0.12065 -0.3048)
			(stroke
				(width 0.1)
				(type default)
			)
			(layer "F.Fab")
		)
		(fp_line
			(start 0.12065 -0.3048)
			(end 0.67945 -0.3048)
			(stroke
				(width 0.1)
				(type default)
			)
			(layer "F.Fab")
		)
		(fp_line
			(start 0.67945 -0.3048)
			(end 0.67945 0.3048)
			(stroke
				(width 0.1)
				(type default)
			)
			(layer "F.Fab")
		)
		(fp_line
			(start -0.67945 -0.305054)
			(end -0.12065 -0.305054)
			(stroke
				(width 0.1)
				(type default)
			)
			(layer "F.Fab")
		)
		(fp_line
			(start -0.12065 -0.305054)
			(end -0.12065 -0.2794)
			(stroke
				(width 0.1)
				(type default)
			)
			(layer "F.Fab")
		)
		(pad "1" smd circle
			(at -0.40005 0 270)
			(size 0 0)
			(layers "F.Cu" "F.Mask" "F.Paste")
			(net "RST_RT_CPU0_P1_PERST_R_N")
		)
		(pad "2" smd circle
			(at 0.40005 0 270)
			(size 0 0)
			(layers "F.Cu" "F.Mask" "F.Paste")
			(net "RST_RT_CPU0_P1_PERST_R2_N")
		)
	)
	(footprint ""
		(layer "F.Cu")
		(at 82.166714 -192.061084 180)
		(property "Reference" "PL28"
			(at -21.355304 3.337306 90)
			(unlocked yes)
			(layer "F.SilkS")
			(effects
				(font
					(size 0.7874 0.5842)
					(thickness 0.1524)
				)
				(justify left)
			)
		)
		(property "Value" ""
			(at 0 0 180)
			(layer "F.Fab")
			(effects
				(font
					(size 1.27 1.27)
				)
			)
		)
		(duplicate_pad_numbers_are_jumpers no)
		(fp_line
			(start 3.750056 5.500116)
			(end 3.750056 -5.500116)
			(stroke
				(width 0.1524)
				(type default)
			)
			(layer "F.SilkS")
		)
		(fp_line
			(start 3.750056 -5.500116)
			(end 2.393442 -5.500116)
			(stroke
				(width 0.1524)
				(type default)
			)
			(layer "F.SilkS")
		)
		(fp_line
			(start 2.393442 5.500116)
			(end 3.750056 5.500116)
			(stroke
				(width 0.1524)
				(type default)
			)
			(layer "F.SilkS")
		)
		(fp_line
			(start -2.393442 5.500116)
			(end -3.750056 5.500116)
			(stroke
				(width 0.1524)
				(type default)
			)
			(layer "F.SilkS")
		)
		(fp_line
			(start -3.750056 5.500116)
			(end -3.750056 -5.500116)
			(stroke
				(width 0.1524)
				(type default)
			)
			(layer "F.SilkS")
		)
		(fp_line
			(start -3.750056 -5.500116)
			(end -2.393442 -5.500116)
			(stroke
				(width 0.1524)
				(type default)
			)
			(layer "F.SilkS")
		)
		(fp_poly
			(pts
				(xy -3.9116 -4.249928) (xy -4.445 -3.983228) (xy -4.445 -4.516628)
			)
			(stroke
				(width 0)
				(type default)
			)
			(fill yes)
			(layer "F.SilkS")
		)
		(fp_line
			(start 3.750056 5.500116)
			(end 3.750056 -5.500116)
			(stroke
				(width 0.1)
				(type default)
			)
			(layer "F.Fab")
		)
		(fp_line
			(start 3.750056 -5.500116)
			(end -3.750056 -5.500116)
			(stroke
				(width 0.1)
				(type default)
			)
			(layer "F.Fab")
		)
		(fp_line
			(start -3.750056 5.500116)
			(end 3.750056 5.500116)
			(stroke
				(width 0.1)
				(type default)
			)
			(layer "F.Fab")
		)
		(fp_line
			(start -3.750056 -5.500116)
			(end -3.750056 5.500116)
			(stroke
				(width 0.1)
				(type default)
			)
			(layer "F.Fab")
		)
		(fp_poly
			(pts
				(xy -4.9276 -4.757928) (xy -4.9276 -3.741928) (xy -3.9116 -4.249928)
			)
			(stroke
				(width 0)
				(type default)
			)
			(fill yes)
			(layer "F.Fab")
		)
		(pad "1" smd rect
			(at 0 -4.249928 90)
			(size 2.413 4.5212)
			(layers "F.Cu" "F.Mask" "F.Paste")
			(net "SW_PVDDCR_CPU0_P1_SW1")
		)
		(pad "2" smd rect
			(at 0 -1.175004 90)
			(size 1.3716 4.5212)
			(layers "F.Cu" "F.Mask" "F.Paste")
			(net "IND_CPU0_P1_CPL5")
		)
		(pad "3" smd rect
			(at 0 1.175004 90)
			(size 1.3716 4.5212)
			(layers "F.Cu" "F.Mask" "F.Paste")
			(net "IND_CPU0_P1_CPL1")
		)
		(pad "4" smd rect
			(at 0 4.249928 90)
			(size 2.413 4.5212)
			(layers "F.Cu" "F.Mask" "F.Paste")
			(net "PVDDCR_CPU0_P1")
		)
	)
	(footprint ""
		(layer "F.Cu")
		(at 40.386 -391.7696 -90)
		(property "Reference" "R6725"
			(at 0 0 270)
			(layer "F.SilkS")
			(hide yes)
			(effects
				(font
					(size 1.27 1.27)
				)
			)
		)
		(property "Value" ""
			(at 0 0 270)
			(layer "F.Fab")
			(effects
				(font
					(size 1.27 1.27)
				)
			)
		)
		(duplicate_pad_numbers_are_jumpers no)
		(fp_line
			(start -0.32512 0.175006)
			(end -0.32512 -0.175006)
			(stroke
				(width 0.1)
				(type default)
			)
			(layer "F.Fab")
		)
		(fp_line
			(start 0.32512 0.175006)
			(end -0.32512 0.175006)
			(stroke
				(width 0.1)
				(type default)
			)
			(layer "F.Fab")
		)
		(fp_line
			(start -0.32512 -0.175006)
			(end 0.32512 -0.175006)
			(stroke
				(width 0.1)
				(type default)
			)
			(layer "F.Fab")
		)
		(fp_line
			(start 0.32512 -0.175006)
			(end 0.32512 0.175006)
			(stroke
				(width 0.1)
				(type default)
			)
			(layer "F.Fab")
		)
		(pad "1" smd rect
			(at -0.2667 0 270)
			(size 0.3048 0.381)
			(layers "F.Cu" "F.Mask" "F.Paste")
			(net "P1V8_CPU1_RT_1D")
		)
		(pad "2" smd rect
			(at 0.2667 0 90)
			(size 0.3048 0.381)
			(layers "F.Cu" "F.Mask" "F.Paste")
			(net "JTAG_TEST_MODE_RT_CPU1_P0")
		)
	)
	(footprint ""
		(layer "F.Cu")
		(at 54.809644 -408.517344 -90)
		(property "Reference" "C6633"
			(at 0 0 270)
			(layer "F.SilkS")
			(hide yes)
			(effects
				(font
					(size 1.27 1.27)
				)
			)
		)
		(property "Value" ""
			(at 0 0 270)
			(layer "F.Fab")
			(effects
				(font
					(size 1.27 1.27)
				)
			)
		)
		(duplicate_pad_numbers_are_jumpers no)
		(fp_line
			(start -0.299974 0.150114)
			(end -0.299974 -0.150114)
			(stroke
				(width 0.1)
				(type default)
			)
			(layer "F.Fab")
		)
		(fp_line
			(start 0.299974 0.150114)
			(end -0.299974 0.150114)
			(stroke
				(width 0.1)
				(type default)
			)
			(layer "F.Fab")
		)
		(fp_line
			(start -0.299974 -0.150114)
			(end 0.299974 -0.150114)
			(stroke
				(width 0.1)
				(type default)
			)
			(layer "F.Fab")
		)
		(fp_line
			(start 0.299974 -0.150114)
			(end 0.299974 0.150114)
			(stroke
				(width 0.1)
				(type default)
			)
			(layer "F.Fab")
		)
		(pad "1" smd rect
			(at -0.2667 0 270)
			(size 0.3048 0.381)
			(layers "F.Cu" "F.Mask" "F.Paste")
			(net "P5E_CPU1_P0_TX_BUF_C_DP<2>")
		)
		(pad "2" smd rect
			(at 0.2667 0 270)
			(size 0.3048 0.381)
			(layers "F.Cu" "F.Mask" "F.Paste")
			(net "P5E_CPU1_P0_TX_BUF_DP<2>")
		)
	)
	(footprint ""
		(layer "F.Cu")
		(at 99.080828 -395.6304 -90)
		(property "Reference" "R6730"
			(at 0 0 270)
			(layer "F.SilkS")
			(hide yes)
			(effects
				(font
					(size 1.27 1.27)
				)
			)
		)
		(property "Value" ""
			(at 0 0 270)
			(layer "F.Fab")
			(effects
				(font
					(size 1.27 1.27)
				)
			)
		)
		(duplicate_pad_numbers_are_jumpers no)
		(fp_line
			(start -0.32512 0.175006)
			(end -0.32512 -0.175006)
			(stroke
				(width 0.1)
				(type default)
			)
			(layer "F.Fab")
		)
		(fp_line
			(start 0.32512 0.175006)
			(end -0.32512 0.175006)
			(stroke
				(width 0.1)
				(type default)
			)
			(layer "F.Fab")
		)
		(fp_line
			(start -0.32512 -0.175006)
			(end 0.32512 -0.175006)
			(stroke
				(width 0.1)
				(type default)
			)
			(layer "F.Fab")
		)
		(fp_line
			(start 0.32512 -0.175006)
			(end 0.32512 0.175006)
			(stroke
				(width 0.1)
				(type default)
			)
			(layer "F.Fab")
		)
		(pad "1" smd rect
			(at -0.2667 0 270)
			(size 0.3048 0.381)
			(layers "F.Cu" "F.Mask" "F.Paste")
			(net "P1V8_CPU1_RT_1D")
		)
		(pad "2" smd rect
			(at 0.2667 0 90)
			(size 0.3048 0.381)
			(layers "F.Cu" "F.Mask" "F.Paste")
			(net "RT_CPU1_P1_VQPS")
		)
	)
	(footprint ""
		(layer "F.Cu")
		(at 360.098594 -320.132964 90)
		(property "Reference" "R8306"
			(at 0 0 90)
			(layer "F.SilkS")
			(hide yes)
			(effects
				(font
					(size 1.27 1.27)
				)
			)
		)
		(property "Value" ""
			(at 0 0 90)
			(layer "F.Fab")
			(effects
				(font
					(size 1.27 1.27)
				)
			)
		)
		(duplicate_pad_numbers_are_jumpers no)
		(fp_line
			(start 0.7874 -0.4064)
			(end 0.7874 -0.053594)
			(stroke
				(width 0.1524)
				(type default)
			)
			(layer "F.SilkS")
		)
		(fp_line
			(start -0.7874 -0.4064)
			(end 0.7874 -0.4064)
			(stroke
				(width 0.1524)
				(type default)
			)
			(layer "F.SilkS")
		)
		(fp_line
			(start -0.7874 0.022606)
			(end -0.7874 -0.4064)
			(stroke
				(width 0.1524)
				(type default)
			)
			(layer "F.SilkS")
		)
		(fp_line
			(start 0.364236 0.4064)
			(end -0.372364 0.4064)
			(stroke
				(width 0.1524)
				(type default)
			)
			(layer "F.SilkS")
		)
		(fp_line
			(start -0.12065 -0.305054)
			(end -0.12065 -0.2794)
			(stroke
				(width 0.1)
				(type default)
			)
			(layer "F.Fab")
		)
		(fp_line
			(start -0.67945 -0.305054)
			(end -0.12065 -0.305054)
			(stroke
				(width 0.1)
				(type default)
			)
			(layer "F.Fab")
		)
		(fp_line
			(start 0.67945 -0.3048)
			(end 0.67945 0.3048)
			(stroke
				(width 0.1)
				(type default)
			)
			(layer "F.Fab")
		)
		(fp_line
			(start 0.12065 -0.3048)
			(end 0.67945 -0.3048)
			(stroke
				(width 0.1)
				(type default)
			)
			(layer "F.Fab")
		)
		(fp_line
			(start 0.12065 -0.2794)
			(end 0.12065 -0.3048)
			(stroke
				(width 0.1)
				(type default)
			)
			(layer "F.Fab")
		)
		(fp_line
			(start -0.12065 -0.2794)
			(end 0.12065 -0.2794)
			(stroke
				(width 0.1)
				(type default)
			)
			(layer "F.Fab")
		)
		(fp_line
			(start 0.120396 0.2794)
			(end -0.12065 0.2794)
			(stroke
				(width 0.1)
				(type default)
			)
			(layer "F.Fab")
		)
		(fp_line
			(start -0.12065 0.2794)
			(end -0.12065 0.3048)
			(stroke
				(width 0.1)
				(type default)
			)
			(layer "F.Fab")
		)
		(fp_line
			(start 0.67945 0.3048)
			(end 0.120396 0.3048)
			(stroke
				(width 0.1)
				(type default)
			)
			(layer "F.Fab")
		)
		(fp_line
			(start 0.120396 0.3048)
			(end 0.120396 0.2794)
			(stroke
				(width 0.1)
				(type default)
			)
			(layer "F.Fab")
		)
		(fp_line
			(start -0.12065 0.3048)
			(end -0.67945 0.3048)
			(stroke
				(width 0.1)
				(type default)
			)
			(layer "F.Fab")
		)
		(fp_line
			(start -0.67945 0.3048)
			(end -0.67945 -0.305054)
			(stroke
				(width 0.1)
				(type default)
			)
			(layer "F.Fab")
		)
		(pad "1" smd circle
			(at -0.40005 0 90)
			(size 0 0)
			(layers "F.Cu" "F.Mask" "F.Paste")
			(net "CLK_100M_CPU0_CLK13_R_DN")
		)
		(pad "2" smd circle
			(at 0.40005 0 90)
			(size 0 0)
			(layers "F.Cu" "F.Mask" "F.Paste")
			(net "CLK_100M_CPU0_CLK13_DN")
		)
	)
)
